(kicad_pcb
	(version 20241229)
	(generator "pcbnew")
	(generator_version "9.0")
	(general
		(thickness 1.599998)
		(legacy_teardrops no)
	)
	(paper "A4")
	(title_block
		(title "Artix - Datacenter Secure Control Module (DC-SCM)")
		(date "2024-11-06")
		(rev "1.1.3")
		(comment 9 "footprints 399-405 of 544")
	)
	(layers
		(0 "F.Cu" signal)
		(4 "In1.Cu" signal)
		(6 "In2.Cu" signal)
		(8 "In3.Cu" signal)
		(10 "In4.Cu" signal)
		(12 "In5.Cu" signal)
		(14 "In6.Cu" signal)
		(2 "B.Cu" signal)
		(9 "F.Adhes" user "F.Adhesive")
		(11 "B.Adhes" user "B.Adhesive")
		(13 "F.Paste" user)
		(15 "B.Paste" user)
		(5 "F.SilkS" user "F.Silkscreen")
		(7 "B.SilkS" user "B.Silkscreen")
		(1 "F.Mask" user)
		(3 "B.Mask" user)
		(17 "Dwgs.User" user "User.Drawings")
		(19 "Cmts.User" user "User.Comments")
		(21 "Eco1.User" user "User.Eco1")
		(23 "Eco2.User" user "User.Eco2")
		(25 "Edge.Cuts" user)
		(27 "Margin" user)
		(31 "F.CrtYd" user "F.Courtyard")
		(29 "B.CrtYd" user "B.Courtyard")
		(35 "F.Fab" user)
		(33 "B.Fab" user)
	)
	(footprint "antmicro-footprints:R_0402_1005Metric"
		(layer "B.Cu")
		(at 71.21 139.315)
		(descr "Resistor SMD 0402")
		(tags "resistor SMD 0402")
		(property "Reference" "R43"
			(at -2.95 0.425 0)
			(layer "B.SilkS")
			(effects
				(font
					(size 0.7 0.7)
					(thickness 0.15)
				)
				(justify right bottom mirror)
			)
		)
		(property "Value" "R_10k_0402"
			(at 0 -1.4 0)
			(layer "B.Fab")
			(effects
				(font
					(size 0.7 0.7)
					(thickness 0.15)
				)
				(justify right bottom mirror)
			)
		)
		(property "Datasheet" "https://www.bourns.com/docs/product-datasheets/cr.pdf"
			(at 0 0 0)
			(layer "F.Fab")
			(hide yes)
			(effects
				(font
					(size 1.27 1.27)
					(thickness 0.15)
				)
			)
		)
		(property "Description" "SMD Chip Resistor, 10 kohm, ± 1%, 62.5 mW, 0402 [1005 Metric], Thick Film, General Purpose"
			(at 0 0 0)
			(layer "F.Fab")
			(hide yes)
			(effects
				(font
					(size 1.27 1.27)
					(thickness 0.15)
				)
			)
		)
		(property "Author" "Antmicro"
			(at 0 0 0)
			(layer "B.Fab")
			(hide yes)
			(effects
				(font
					(size 1 1)
					(thickness 0.15)
				)
				(justify mirror)
			)
		)
		(property "License" "Apache-2.0"
			(at 0 0 0)
			(layer "B.Fab")
			(hide yes)
			(effects
				(font
					(size 1 1)
					(thickness 0.15)
				)
				(justify mirror)
			)
		)
		(property "MPN" "CR0402-FX-1002GLF"
			(at 0 0 0)
			(layer "B.Fab")
			(hide yes)
			(effects
				(font
					(size 1 1)
					(thickness 0.15)
				)
				(justify mirror)
			)
		)
		(property "Manufacturer" "Bourns"
			(at 0 0 0)
			(layer "B.Fab")
			(hide yes)
			(effects
				(font
					(size 1 1)
					(thickness 0.15)
				)
				(justify mirror)
			)
		)
		(property "Tolerance" "1%"
			(at 0 0 0)
			(layer "B.Fab")
			(hide yes)
			(effects
				(font
					(size 1 1)
					(thickness 0.15)
				)
				(justify mirror)
			)
		)
		(property "Val" "10k"
			(at 0 0 0)
			(layer "B.Fab")
			(hide yes)
			(effects
				(font
					(size 1 1)
					(thickness 0.15)
				)
				(justify mirror)
			)
		)
		(sheetname "/RoT/")
		(sheetfile "rot.kicad_sch")
		(attr smd)
		(fp_rect
			(start -0.925 0.47)
			(end 0.925 -0.47)
			(stroke
				(width 0.05)
				(type default)
			)
			(fill no)
			(layer "B.CrtYd")
		)
		(fp_rect
			(start -0.5 0.25)
			(end 0.5 -0.25)
			(stroke
				(width 0.15)
				(type solid)
			)
			(fill no)
			(layer "B.Fab")
		)
		(pad "1" smd roundrect
			(at -0.48 0)
			(size 0.59 0.64)
			(layers "B.Cu" "B.Mask" "B.Paste")
			(roundrect_rratio 0.25)
			(net 137 "QSPIA2_D1")
			(pintype "passive")
		)
		(pad "2" smd roundrect
			(at 0.48 0)
			(size 0.59 0.64)
			(layers "B.Cu" "B.Mask" "B.Paste")
			(roundrect_rratio 0.25)
			(net 2 "VCC3V3")
			(pintype "passive")
		)
	)
	(footprint "antmicro-footprints:R_0402_1005Metric"
		(layer "B.Cu")
		(at 71.21 137.315)
		(descr "Resistor SMD 0402")
		(tags "resistor SMD 0402")
		(property "Reference" "R39"
			(at -2.95 0.425 0)
			(layer "B.SilkS")
			(effects
				(font
					(size 0.7 0.7)
					(thickness 0.15)
				)
				(justify right bottom mirror)
			)
		)
		(property "Value" "R_10k_0402"
			(at 0 -1.4 0)
			(layer "B.Fab")
			(effects
				(font
					(size 0.7 0.7)
					(thickness 0.15)
				)
				(justify right bottom mirror)
			)
		)
		(property "Datasheet" "https://www.bourns.com/docs/product-datasheets/cr.pdf"
			(at 0 0 0)
			(layer "F.Fab")
			(hide yes)
			(effects
				(font
					(size 1.27 1.27)
					(thickness 0.15)
				)
			)
		)
		(property "Description" "SMD Chip Resistor, 10 kohm, ± 1%, 62.5 mW, 0402 [1005 Metric], Thick Film, General Purpose"
			(at 0 0 0)
			(layer "F.Fab")
			(hide yes)
			(effects
				(font
					(size 1.27 1.27)
					(thickness 0.15)
				)
			)
		)
		(property "Author" "Antmicro"
			(at 0 0 0)
			(layer "B.Fab")
			(hide yes)
			(effects
				(font
					(size 1 1)
					(thickness 0.15)
				)
				(justify mirror)
			)
		)
		(property "License" "Apache-2.0"
			(at 0 0 0)
			(layer "B.Fab")
			(hide yes)
			(effects
				(font
					(size 1 1)
					(thickness 0.15)
				)
				(justify mirror)
			)
		)
		(property "MPN" "CR0402-FX-1002GLF"
			(at 0 0 0)
			(layer "B.Fab")
			(hide yes)
			(effects
				(font
					(size 1 1)
					(thickness 0.15)
				)
				(justify mirror)
			)
		)
		(property "Manufacturer" "Bourns"
			(at 0 0 0)
			(layer "B.Fab")
			(hide yes)
			(effects
				(font
					(size 1 1)
					(thickness 0.15)
				)
				(justify mirror)
			)
		)
		(property "Tolerance" "1%"
			(at 0 0 0)
			(layer "B.Fab")
			(hide yes)
			(effects
				(font
					(size 1 1)
					(thickness 0.15)
				)
				(justify mirror)
			)
		)
		(property "Val" "10k"
			(at 0 0 0)
			(layer "B.Fab")
			(hide yes)
			(effects
				(font
					(size 1 1)
					(thickness 0.15)
				)
				(justify mirror)
			)
		)
		(sheetname "/RoT/")
		(sheetfile "rot.kicad_sch")
		(attr smd)
		(fp_rect
			(start -0.925 0.47)
			(end 0.925 -0.47)
			(stroke
				(width 0.05)
				(type default)
			)
			(fill no)
			(layer "B.CrtYd")
		)
		(fp_rect
			(start -0.5 0.25)
			(end 0.5 -0.25)
			(stroke
				(width 0.15)
				(type solid)
			)
			(fill no)
			(layer "B.Fab")
		)
		(pad "1" smd roundrect
			(at -0.48 0)
			(size 0.59 0.64)
			(layers "B.Cu" "B.Mask" "B.Paste")
			(roundrect_rratio 0.25)
			(net 139 "QSPIA2_D3")
			(pintype "passive")
		)
		(pad "2" smd roundrect
			(at 0.48 0)
			(size 0.59 0.64)
			(layers "B.Cu" "B.Mask" "B.Paste")
			(roundrect_rratio 0.25)
			(net 2 "VCC3V3")
			(pintype "passive")
		)
	)
	(footprint "antmicro-footprints:R_0402_1005Metric"
		(layer "B.Cu")
		(at 71.21 140.315)
		(descr "Resistor SMD 0402")
		(tags "resistor SMD 0402")
		(property "Reference" "R35"
			(at -2.95 0.425 0)
			(layer "B.SilkS")
			(effects
				(font
					(size 0.7 0.7)
					(thickness 0.15)
				)
				(justify right bottom mirror)
			)
		)
		(property "Value" "R_10k_0402"
			(at 0 -1.4 0)
			(layer "B.Fab")
			(effects
				(font
					(size 0.7 0.7)
					(thickness 0.15)
				)
				(justify right bottom mirror)
			)
		)
		(property "Datasheet" "https://www.bourns.com/docs/product-datasheets/cr.pdf"
			(at 0 0 0)
			(layer "F.Fab")
			(hide yes)
			(effects
				(font
					(size 1.27 1.27)
					(thickness 0.15)
				)
			)
		)
		(property "Description" "SMD Chip Resistor, 10 kohm, ± 1%, 62.5 mW, 0402 [1005 Metric], Thick Film, General Purpose"
			(at 0 0 0)
			(layer "F.Fab")
			(hide yes)
			(effects
				(font
					(size 1.27 1.27)
					(thickness 0.15)
				)
			)
		)
		(property "Author" "Antmicro"
			(at 0 0 0)
			(layer "B.Fab")
			(hide yes)
			(effects
				(font
					(size 1 1)
					(thickness 0.15)
				)
				(justify mirror)
			)
		)
		(property "License" "Apache-2.0"
			(at 0 0 0)
			(layer "B.Fab")
			(hide yes)
			(effects
				(font
					(size 1 1)
					(thickness 0.15)
				)
				(justify mirror)
			)
		)
		(property "MPN" "CR0402-FX-1002GLF"
			(at 0 0 0)
			(layer "B.Fab")
			(hide yes)
			(effects
				(font
					(size 1 1)
					(thickness 0.15)
				)
				(justify mirror)
			)
		)
		(property "Manufacturer" "Bourns"
			(at 0 0 0)
			(layer "B.Fab")
			(hide yes)
			(effects
				(font
					(size 1 1)
					(thickness 0.15)
				)
				(justify mirror)
			)
		)
		(property "Tolerance" "1%"
			(at 0 0 0)
			(layer "B.Fab")
			(hide yes)
			(effects
				(font
					(size 1 1)
					(thickness 0.15)
				)
				(justify mirror)
			)
		)
		(property "Val" "10k"
			(at 0 0 0)
			(layer "B.Fab")
			(hide yes)
			(effects
				(font
					(size 1 1)
					(thickness 0.15)
				)
				(justify mirror)
			)
		)
		(sheetname "/RoT/")
		(sheetfile "rot.kicad_sch")
		(attr smd)
		(fp_rect
			(start -0.925 0.47)
			(end 0.925 -0.47)
			(stroke
				(width 0.05)
				(type default)
			)
			(fill no)
			(layer "B.CrtYd")
		)
		(fp_rect
			(start -0.5 0.25)
			(end 0.5 -0.25)
			(stroke
				(width 0.15)
				(type solid)
			)
			(fill no)
			(layer "B.Fab")
		)
		(pad "1" smd roundrect
			(at -0.48 0)
			(size 0.59 0.64)
			(layers "B.Cu" "B.Mask" "B.Paste")
			(roundrect_rratio 0.25)
			(net 138 "QSPIA2_D2")
			(pintype "passive")
		)
		(pad "2" smd roundrect
			(at 0.48 0)
			(size 0.59 0.64)
			(layers "B.Cu" "B.Mask" "B.Paste")
			(roundrect_rratio 0.25)
			(net 2 "VCC3V3")
			(pintype "passive")
		)
	)
	(footprint "antmicro-footprints:R_0402_1005Metric"
		(layer "B.Cu")
		(at 71.19 116.125)
		(descr "Resistor SMD 0402")
		(tags "resistor SMD 0402")
		(property "Reference" "R29"
			(at -2.99 0.375 0)
			(layer "B.SilkS")
			(effects
				(font
					(size 0.7 0.7)
					(thickness 0.15)
				)
				(justify right bottom mirror)
			)
		)
		(property "Value" "R_10k_0402"
			(at 0 -1.4 0)
			(layer "B.Fab")
			(effects
				(font
					(size 0.7 0.7)
					(thickness 0.15)
				)
				(justify right bottom mirror)
			)
		)
		(property "Datasheet" "https://www.bourns.com/docs/product-datasheets/cr.pdf"
			(at 0 0 0)
			(layer "F.Fab")
			(hide yes)
			(effects
				(font
					(size 1.27 1.27)
					(thickness 0.15)
				)
			)
		)
		(property "Description" "SMD Chip Resistor, 10 kohm, ± 1%, 62.5 mW, 0402 [1005 Metric], Thick Film, General Purpose"
			(at 0 0 0)
			(layer "F.Fab")
			(hide yes)
			(effects
				(font
					(size 1.27 1.27)
					(thickness 0.15)
				)
			)
		)
		(property "Author" "Antmicro"
			(at 0 0 0)
			(layer "B.Fab")
			(hide yes)
			(effects
				(font
					(size 1 1)
					(thickness 0.15)
				)
				(justify mirror)
			)
		)
		(property "License" "Apache-2.0"
			(at 0 0 0)
			(layer "B.Fab")
			(hide yes)
			(effects
				(font
					(size 1 1)
					(thickness 0.15)
				)
				(justify mirror)
			)
		)
		(property "MPN" "CR0402-FX-1002GLF"
			(at 0 0 0)
			(layer "B.Fab")
			(hide yes)
			(effects
				(font
					(size 1 1)
					(thickness 0.15)
				)
				(justify mirror)
			)
		)
		(property "Manufacturer" "Bourns"
			(at 0 0 0)
			(layer "B.Fab")
			(hide yes)
			(effects
				(font
					(size 1 1)
					(thickness 0.15)
				)
				(justify mirror)
			)
		)
		(property "Tolerance" "1%"
			(at 0 0 0)
			(layer "B.Fab")
			(hide yes)
			(effects
				(font
					(size 1 1)
					(thickness 0.15)
				)
				(justify mirror)
			)
		)
		(property "Val" "10k"
			(at 0 0 0)
			(layer "B.Fab")
			(hide yes)
			(effects
				(font
					(size 1 1)
					(thickness 0.15)
				)
				(justify mirror)
			)
		)
		(sheetname "/RoT/")
		(sheetfile "rot.kicad_sch")
		(attr smd)
		(fp_rect
			(start -0.925 0.47)
			(end 0.925 -0.47)
			(stroke
				(width 0.05)
				(type default)
			)
			(fill no)
			(layer "B.CrtYd")
		)
		(fp_rect
			(start -0.5 0.25)
			(end 0.5 -0.25)
			(stroke
				(width 0.15)
				(type solid)
			)
			(fill no)
			(layer "B.Fab")
		)
		(pad "1" smd roundrect
			(at -0.48 0)
			(size 0.59 0.64)
			(layers "B.Cu" "B.Mask" "B.Paste")
			(roundrect_rratio 0.25)
			(net 125 "QSPIB2_D0")
			(pintype "passive")
		)
		(pad "2" smd roundrect
			(at 0.48 0)
			(size 0.59 0.64)
			(layers "B.Cu" "B.Mask" "B.Paste")
			(roundrect_rratio 0.25)
			(net 2 "VCC3V3")
			(pintype "passive")
		)
	)
	(footprint "antmicro-footprints:R_0402_1005Metric"
		(layer "B.Cu")
		(at 71.19 117.125 180)
		(descr "Resistor SMD 0402")
		(tags "resistor SMD 0402")
		(property "Reference" "R25"
			(at 0.79 -0.375 0)
			(layer "B.SilkS")
			(effects
				(font
					(size 0.7 0.7)
					(thickness 0.15)
				)
				(justify left bottom mirror)
			)
		)
		(property "Value" "R_1k_0402"
			(at 0 -1.4 0)
			(layer "B.Fab")
			(effects
				(font
					(size 0.7 0.7)
					(thickness 0.15)
				)
				(justify left bottom mirror)
			)
		)
		(property "Datasheet" "https://www.bourns.com/docs/product-datasheets/cr.pdf"
			(at 0 0 180)
			(layer "F.Fab")
			(hide yes)
			(effects
				(font
					(size 1.27 1.27)
					(thickness 0.15)
				)
			)
		)
		(property "Description" "SMD Chip Resistor, 1 kohm, ± 1%, 63 mW, 0402 [1005 Metric], Thick Film, General Purpose"
			(at 0 0 180)
			(layer "F.Fab")
			(hide yes)
			(effects
				(font
					(size 1.27 1.27)
					(thickness 0.15)
				)
			)
		)
		(property "Author" "Antmicro"
			(at 142.38 234.25 0)
			(layer "B.Fab")
			(hide yes)
			(effects
				(font
					(size 1 1)
					(thickness 0.15)
				)
				(justify mirror)
			)
		)
		(property "License" "Apache-2.0"
			(at 142.38 234.25 0)
			(layer "B.Fab")
			(hide yes)
			(effects
				(font
					(size 1 1)
					(thickness 0.15)
				)
				(justify mirror)
			)
		)
		(property "MPN" "CR0402-FX-1001GLF"
			(at 142.38 234.25 0)
			(layer "B.Fab")
			(hide yes)
			(effects
				(font
					(size 1 1)
					(thickness 0.15)
				)
				(justify mirror)
			)
		)
		(property "Manufacturer" "Bourns"
			(at 142.38 234.25 0)
			(layer "B.Fab")
			(hide yes)
			(effects
				(font
					(size 1 1)
					(thickness 0.15)
				)
				(justify mirror)
			)
		)
		(property "Tolerance" "1%"
			(at 142.38 234.25 0)
			(layer "B.Fab")
			(hide yes)
			(effects
				(font
					(size 1 1)
					(thickness 0.15)
				)
				(justify mirror)
			)
		)
		(property "Val" "1k"
			(at 142.38 234.25 0)
			(layer "B.Fab")
			(hide yes)
			(effects
				(font
					(size 1 1)
					(thickness 0.15)
				)
				(justify mirror)
			)
		)
		(sheetname "/RoT/")
		(sheetfile "rot.kicad_sch")
		(attr smd)
		(fp_rect
			(start -0.925 0.47)
			(end 0.925 -0.47)
			(stroke
				(width 0.05)
				(type default)
			)
			(fill no)
			(layer "B.CrtYd")
		)
		(fp_rect
			(start -0.5 0.25)
			(end 0.5 -0.25)
			(stroke
				(width 0.15)
				(type solid)
			)
			(fill no)
			(layer "B.Fab")
		)
		(pad "1" smd roundrect
			(at -0.48 0 180)
			(size 0.59 0.64)
			(layers "B.Cu" "B.Mask" "B.Paste")
			(roundrect_rratio 0.25)
			(net 2 "VCC3V3")
			(pintype "passive")
		)
		(pad "2" smd roundrect
			(at 0.48 0 180)
			(size 0.59 0.64)
			(layers "B.Cu" "B.Mask" "B.Paste")
			(roundrect_rratio 0.25)
			(net 119 "QSPIB_CLK")
			(pintype "passive")
		)
	)
	(footprint "antmicro-footprints:R_0402_1005Metric"
		(layer "B.Cu")
		(at 71.19 119.125 180)
		(descr "Resistor SMD 0402")
		(tags "resistor SMD 0402")
		(property "Reference" "R21"
			(at 0.79 -0.375 0)
			(layer "B.SilkS")
			(effects
				(font
					(size 0.7 0.7)
					(thickness 0.15)
				)
				(justify left bottom mirror)
			)
		)
		(property "Value" "R_4k7_0402"
			(at 0 -1.4 0)
			(layer "B.Fab")
			(effects
				(font
					(size 0.7 0.7)
					(thickness 0.15)
				)
				(justify left bottom mirror)
			)
		)
		(property "Datasheet" "https://www.bourns.com/docs/product-datasheets/cr.pdf"
			(at 0 0 180)
			(layer "F.Fab")
			(hide yes)
			(effects
				(font
					(size 1.27 1.27)
					(thickness 0.15)
				)
			)
		)
		(property "Description" "SMD Chip Resistor, 4.7 kohm, ± 1%, 62.5 mW, 0402 [1005 Metric], Thick Film, General Purpose"
			(at 0 0 180)
			(layer "F.Fab")
			(hide yes)
			(effects
				(font
					(size 1.27 1.27)
					(thickness 0.15)
				)
			)
		)
		(property "Author" "Antmicro"
			(at 142.38 238.25 0)
			(layer "B.Fab")
			(hide yes)
			(effects
				(font
					(size 1 1)
					(thickness 0.15)
				)
				(justify mirror)
			)
		)
		(property "License" "Apache-2.0"
			(at 142.38 238.25 0)
			(layer "B.Fab")
			(hide yes)
			(effects
				(font
					(size 1 1)
					(thickness 0.15)
				)
				(justify mirror)
			)
		)
		(property "MPN" "CR0402-FX-4701GLF"
			(at 142.38 238.25 0)
			(layer "B.Fab")
			(hide yes)
			(effects
				(font
					(size 1 1)
					(thickness 0.15)
				)
				(justify mirror)
			)
		)
		(property "Manufacturer" "Bourns"
			(at 142.38 238.25 0)
			(layer "B.Fab")
			(hide yes)
			(effects
				(font
					(size 1 1)
					(thickness 0.15)
				)
				(justify mirror)
			)
		)
		(property "Tolerance" "1%"
			(at 142.38 238.25 0)
			(layer "B.Fab")
			(hide yes)
			(effects
				(font
					(size 1 1)
					(thickness 0.15)
				)
				(justify mirror)
			)
		)
		(property "Val" "4k7"
			(at 142.38 238.25 0)
			(layer "B.Fab")
			(hide yes)
			(effects
				(font
					(size 1 1)
					(thickness 0.15)
				)
				(justify mirror)
			)
		)
		(sheetname "/RoT/")
		(sheetfile "rot.kicad_sch")
		(attr smd)
		(fp_rect
			(start -0.925 0.47)
			(end 0.925 -0.47)
			(stroke
				(width 0.05)
				(type default)
			)
			(fill no)
			(layer "B.CrtYd")
		)
		(fp_rect
			(start -0.5 0.25)
			(end 0.5 -0.25)
			(stroke
				(width 0.15)
				(type solid)
			)
			(fill no)
			(layer "B.Fab")
		)
		(pad "1" smd roundrect
			(at -0.48 0 180)
			(size 0.59 0.64)
			(layers "B.Cu" "B.Mask" "B.Paste")
			(roundrect_rratio 0.25)
			(net 2 "VCC3V3")
			(pintype "passive")
		)
		(pad "2" smd roundrect
			(at 0.48 0 180)
			(size 0.59 0.64)
			(layers "B.Cu" "B.Mask" "B.Paste")
			(roundrect_rratio 0.25)
			(net 129 "QSPIB2_CS_N")
			(pintype "passive")
		)
	)
	(footprint "antmicro-footprints:R_0402_1005Metric"
		(layer "B.Cu")
		(at 71.19 120.125)
		(descr "Resistor SMD 0402")
		(tags "resistor SMD 0402")
		(property "Reference" "R41"
			(at -2.99 0.375 0)
			(layer "B.SilkS")
			(effects
				(font
					(size 0.7 0.7)
					(thickness 0.15)
				)
				(justify right bottom mirror)
			)
		)
		(property "Value" "R_10k_0402"
			(at 0 -1.4 0)
			(layer "B.Fab")
			(effects
				(font
					(size 0.7 0.7)
					(thickness 0.15)
				)
				(justify right bottom mirror)
			)
		)
		(property "Datasheet" "https://www.bourns.com/docs/product-datasheets/cr.pdf"
			(at 0 0 0)
			(layer "F.Fab")
			(hide yes)
			(effects
				(font
					(size 1.27 1.27)
					(thickness 0.15)
				)
			)
		)
		(property "Description" "SMD Chip Resistor, 10 kohm, ± 1%, 62.5 mW, 0402 [1005 Metric], Thick Film, General Purpose"
			(at 0 0 0)
			(layer "F.Fab")
			(hide yes)
			(effects
				(font
					(size 1.27 1.27)
					(thickness 0.15)
				)
			)
		)
		(property "Author" "Antmicro"
			(at 0 0 0)
			(layer "B.Fab")
			(hide yes)
			(effects
				(font
					(size 1 1)
					(thickness 0.15)
				)
				(justify mirror)
			)
		)
		(property "License" "Apache-2.0"
			(at 0 0 0)
			(layer "B.Fab")
			(hide yes)
			(effects
				(font
					(size 1 1)
					(thickness 0.15)
				)
				(justify mirror)
			)
		)
		(property "MPN" "CR0402-FX-1002GLF"
			(at 0 0 0)
			(layer "B.Fab")
			(hide yes)
			(effects
				(font
					(size 1 1)
					(thickness 0.15)
				)
				(justify mirror)
			)
		)
		(property "Manufacturer" "Bourns"
			(at 0 0 0)
			(layer "B.Fab")
			(hide yes)
			(effects
				(font
					(size 1 1)
					(thickness 0.15)
				)
				(justify mirror)
			)
		)
		(property "Tolerance" "1%"
			(at 0 0 0)
			(layer "B.Fab")
			(hide yes)
			(effects
				(font
					(size 1 1)
					(thickness 0.15)
				)
				(justify mirror)
			)
		)
		(property "Val" "10k"
			(at 0 0 0)
			(layer "B.Fab")
			(hide yes)
			(effects
				(font
					(size 1 1)
					(thickness 0.15)
				)
				(justify mirror)
			)
		)
		(sheetname "/RoT/")
		(sheetfile "rot.kicad_sch")
		(attr smd)
		(fp_rect
			(start -0.925 0.47)
			(end 0.925 -0.47)
			(stroke
				(width 0.05)
				(type default)
			)
			(fill no)
			(layer "B.CrtYd")
		)
		(fp_rect
			(start -0.5 0.25)
			(end 0.5 -0.25)
			(stroke
				(width 0.15)
				(type solid)
			)
			(fill no)
			(layer "B.Fab")
		)
		(pad "1" smd roundrect
			(at -0.48 0)
			(size 0.59 0.64)
			(layers "B.Cu" "B.Mask" "B.Paste")
			(roundrect_rratio 0.25)
			(net 126 "QSPIB2_D1")
			(pintype "passive")
		)
		(pad "2" smd roundrect
			(at 0.48 0)
			(size 0.59 0.64)
			(layers "B.Cu" "B.Mask" "B.Paste")
			(roundrect_rratio 0.25)
			(net 2 "VCC3V3")
			(pintype "passive")
		)
	)
)
